# BASEBOARD_FAB2 (Tioga Pass) — schematic netlist excerpt (pin names and nets, part order shuffled) for the footprints in the layout excerpt that follows; sources: Cadence DE-HDL packaged netlist, KiCad conversion of Wiwynn_Tioga_Pass_MB.brd

C4D19  CAP_A  0.1UF 16V 10% X7R  pkg 0402V  page 201 : A = VR_PVCCIN_CPU0_VDD ; B = GND
RF23  RES  1.0K 0.1% CHIP  pkg 0402  page 235 : A = VR_PVNN_PCH_AIREF1 ; B = ISENSE_PVNN_PCH_PH1_IMON
R3D21  RES  64.9 1.0% CHIP  pkg 0402  page 96 : A = PVDDQ_GHJ ; B = PWRGD_CPU1_DRAMPWROK_GHJ_G

(kicad_pcb
	(version 20260206)
	(generator "pcbnew")
	(generator_version "10.0")
	(general
		(thickness 1.6)
		(legacy_teardrops no)
	)
	(paper "A4")
	(title_block
		(title "Wiwynn_Tioga_Pass_MB.brd")
		(comment 1 "Tioga Pass / footprints 1260-1262 of 4770")
	)
	(layers
		(0 "F.Cu" signal "TOP")
		(4 "In1.Cu" signal "L2GND")
		(6 "In2.Cu" signal "L3")
		(8 "In3.Cu" signal "L4GND")
		(10 "In4.Cu" signal "L5")
		(12 "In5.Cu" signal "L6GND")
		(14 "In6.Cu" signal "L7VCC")
		(16 "In7.Cu" signal "L8VCC")
		(18 "In8.Cu" signal "L9GND")
		(20 "In9.Cu" signal "L10")
		(22 "In10.Cu" signal "L11GND")
		(24 "In11.Cu" signal "L12")
		(26 "In12.Cu" signal "L13GND")
		(2 "B.Cu" signal "BOTTOM")
		(9 "F.Adhes" user "F.Adhesive")
		(11 "B.Adhes" user "B.Adhesive")
		(13 "F.Paste" user "Package Geometry/Pastemask Top")
		(15 "B.Paste" user "Package Geometry/Pastemask Bottom")
		(5 "F.SilkS" user "Ref Des/Silkscreen Top")
		(7 "B.SilkS" user "Ref Des/Silkscreen Bottom")
		(1 "F.Mask" user "Board Geometry/Soldermask Top")
		(3 "B.Mask" user "Board Geometry/Soldermask Bottom")
		(17 "Dwgs.User" user "User.Drawings")
		(19 "Cmts.User" user "User.Comments")
		(21 "Eco1.User" user "User.Eco1")
		(23 "Eco2.User" user "User.Eco2")
		(25 "Edge.Cuts" user "Board Geometry/Outline")
		(27 "Margin" user)
		(31 "F.CrtYd" user "Package Geometry/Place Bound Top")
		(29 "B.CrtYd" user "Package Geometry/Place Bound Bottom")
		(35 "F.Fab" user "Ref Des/Assembly Top")
		(33 "B.Fab" user "Ref Des/Assembly Bottom")
	)
	(footprint ""
		(layer "F.Cu")
		(at 181.1147 -75.68565 -90)
		(property "Reference" "C4D19"
			(at 0 0 270)
			(layer "F.SilkS")
			(hide yes)
			(effects
				(font
					(size 1.27 1.27)
				)
			)
		)
		(property "Value" ""
			(at 0 0 270)
			(layer "F.Fab")
			(effects
				(font
					(size 1.27 1.27)
				)
			)
		)
		(duplicate_pad_numbers_are_jumpers no)
		(fp_rect
			(start 0.3048 0.9906)
			(end -0.3048 -0.1016)
			(stroke
				(width 0)
				(type default)
			)
			(fill no)
			(layer "F.CrtYd")
		)
		(fp_line
			(start -0.3048 0.9906)
			(end 0.3048 0.9906)
			(stroke
				(width 0.1)
				(type default)
			)
			(layer "F.Fab")
		)
		(fp_line
			(start 0.3048 0.9906)
			(end 0.3048 -0.1016)
			(stroke
				(width 0.1)
				(type default)
			)
			(layer "F.Fab")
		)
		(fp_line
			(start -0.3048 -0.1016)
			(end -0.3048 0.9906)
			(stroke
				(width 0.1)
				(type default)
			)
			(layer "F.Fab")
		)
		(fp_line
			(start 0.3048 -0.1016)
			(end -0.3048 -0.1016)
			(stroke
				(width 0.1)
				(type default)
			)
			(layer "F.Fab")
		)
		(pad "1" smd rect
			(at 0 0 270)
			(size 0.508 0.508)
			(layers "F.Cu" "F.Mask" "F.Paste")
			(net "VR_PVCCIN_CPU0_VDD")
		)
		(pad "2" smd rect
			(at 0 0.889 270)
			(size 0.508 0.508)
			(layers "F.Cu" "F.Mask" "F.Paste")
			(net "GND")
		)
		(zone
			(layer "F.Cu")
			(hatch none 0.5)
			(connect_pads
				(clearance 0)
			)
			(min_thickness 0.25)
			(keepout
				(tracks allowed)
				(vias not_allowed)
				(pads allowed)
				(copperpour not_allowed)
				(footprints allowed)
			)
			(placement
				(enabled no)
				(sheetname "")
			)
			(fill
				(thermal_gap 0.5)
				(thermal_bridge_width 0.5)
				(island_removal_mode 0)
			)
			(polygon
				(pts
					(xy 180.4797 -75.43165) (xy 180.8607 -75.43165) (xy 180.8607 -75.93965) (xy 180.4797 -75.93965)
				)
			)
		)
		(zone
			(layer "F.Cu")
			(hatch none 0.5)
			(connect_pads
				(clearance 0)
			)
			(min_thickness 0.25)
			(keepout
				(tracks not_allowed)
				(vias allowed)
				(pads allowed)
				(copperpour not_allowed)
				(footprints allowed)
			)
			(placement
				(enabled no)
				(sheetname "")
			)
			(fill
				(thermal_gap 0.5)
				(thermal_bridge_width 0.5)
				(island_removal_mode 0)
			)
			(polygon
				(pts
					(xy 180.4797 -75.43165) (xy 180.8607 -75.43165) (xy 180.8607 -75.93965) (xy 180.4797 -75.93965)
				)
			)
		)
	)
	(footprint ""
		(layer "F.Cu")
		(at 163.592764 -70.694296 -90)
		(property "Reference" "R3D21"
			(at 0 0 270)
			(layer "F.SilkS")
			(hide yes)
			(effects
				(font
					(size 1.27 1.27)
				)
			)
		)
		(property "Value" ""
			(at 0 0 270)
			(layer "F.Fab")
			(effects
				(font
					(size 1.27 1.27)
				)
			)
		)
		(duplicate_pad_numbers_are_jumpers no)
		(fp_poly
			(pts
				(xy -0.2794 -0.1016) (xy 0.2794 -0.1016) (xy 0.2794 0.9906) (xy -0.2794 0.9906)
			)
			(stroke
				(width 0)
				(type default)
			)
			(fill no)
			(layer "F.CrtYd")
		)
		(fp_line
			(start -0.2794 0.9906)
			(end 0.2794 0.9906)
			(stroke
				(width 0.1)
				(type default)
			)
			(layer "F.Fab")
		)
		(fp_line
			(start 0.2794 0.9906)
			(end 0.2794 -0.1016)
			(stroke
				(width 0.1)
				(type default)
			)
			(layer "F.Fab")
		)
		(fp_line
			(start -0.2794 -0.1016)
			(end -0.2794 0.9906)
			(stroke
				(width 0.1)
				(type default)
			)
			(layer "F.Fab")
		)
		(fp_line
			(start 0.2794 -0.1016)
			(end -0.2794 -0.1016)
			(stroke
				(width 0.1)
				(type default)
			)
			(layer "F.Fab")
		)
		(pad "1" smd rect
			(at 0 0 270)
			(size 0.508 0.508)
			(layers "F.Cu" "F.Mask" "F.Paste")
			(net "PVDDQ_GHJ")
		)
		(pad "2" smd rect
			(at 0 0.889 270)
			(size 0.508 0.508)
			(layers "F.Cu" "F.Mask" "F.Paste")
			(net "PWRGD_CPU1_DRAMPWROK_GHJ_G")
		)
		(zone
			(layer "F.Cu")
			(hatch none 0.5)
			(connect_pads
				(clearance 0)
			)
			(min_thickness 0.25)
			(keepout
				(tracks not_allowed)
				(vias allowed)
				(pads allowed)
				(copperpour not_allowed)
				(footprints allowed)
			)
			(placement
				(enabled no)
				(sheetname "")
			)
			(fill
				(thermal_gap 0.5)
				(thermal_bridge_width 0.5)
				(island_removal_mode 0)
			)
			(polygon
				(pts
					(xy 162.957764 -70.948296) (xy 162.957764 -70.440296) (xy 163.338764 -70.440296) (xy 163.338764 -70.948296)
				)
			)
		)
		(zone
			(layer "F.Cu")
			(hatch none 0.5)
			(connect_pads
				(clearance 0)
			)
			(min_thickness 0.25)
			(keepout
				(tracks allowed)
				(vias not_allowed)
				(pads allowed)
				(copperpour not_allowed)
				(footprints allowed)
			)
			(placement
				(enabled no)
				(sheetname "")
			)
			(fill
				(thermal_gap 0.5)
				(thermal_bridge_width 0.5)
				(island_removal_mode 0)
			)
			(polygon
				(pts
					(xy 163.338764 -70.948296) (xy 163.338764 -70.440296) (xy 162.957764 -70.440296) (xy 162.957764 -70.948296)
				)
			)
		)
	)
	(footprint ""
		(layer "F.Cu")
		(at 398.768316 -157.664658 -90)
		(property "Reference" "RF23"
			(at -0.8382 -0.67818 270)
			(unlocked yes)
			(layer "F.SilkS")
			(effects
				(font
					(size 0.4064 0.254)
					(thickness 0.1524)
				)
				(justify left)
			)
		)
		(property "Value" ""
			(at 0 0 270)
			(layer "F.Fab")
			(effects
				(font
					(size 1.27 1.27)
				)
			)
		)
		(duplicate_pad_numbers_are_jumpers no)
		(fp_poly
			(pts
				(xy -0.2794 -0.1016) (xy 0.2794 -0.1016) (xy 0.2794 0.9906) (xy -0.2794 0.9906)
			)
			(stroke
				(width 0)
				(type default)
			)
			(fill no)
			(layer "F.CrtYd")
		)
		(fp_line
			(start -0.2794 0.9906)
			(end 0.2794 0.9906)
			(stroke
				(width 0.1)
				(type default)
			)
			(layer "F.Fab")
		)
		(fp_line
			(start 0.2794 0.9906)
			(end 0.2794 -0.1016)
			(stroke
				(width 0.1)
				(type default)
			)
			(layer "F.Fab")
		)
		(fp_line
			(start -0.2794 -0.1016)
			(end -0.2794 0.9906)
			(stroke
				(width 0.1)
				(type default)
			)
			(layer "F.Fab")
		)
		(fp_line
			(start 0.2794 -0.1016)
			(end -0.2794 -0.1016)
			(stroke
				(width 0.1)
				(type default)
			)
			(layer "F.Fab")
		)
		(pad "1" smd rect
			(at 0 0 270)
			(size 0.508 0.508)
			(layers "F.Cu" "F.Mask" "F.Paste")
			(net "VR_PVNN_PCH_AIREF1")
		)
		(pad "2" smd rect
			(at 0 0.889 270)
			(size 0.508 0.508)
			(layers "F.Cu" "F.Mask" "F.Paste")
			(net "ISENSE_PVNN_PCH_PH1_IMON")
		)
		(zone
			(layer "F.Cu")
			(hatch none 0.5)
			(connect_pads
				(clearance 0)
			)
			(min_thickness 0.25)
			(keepout
				(tracks not_allowed)
				(vias allowed)
				(pads allowed)
				(copperpour not_allowed)
				(footprints allowed)
			)
			(placement
				(enabled no)
				(sheetname "")
			)
			(fill
				(thermal_gap 0.5)
				(thermal_bridge_width 0.5)
				(island_removal_mode 0)
			)
			(polygon
				(pts
					(xy 398.133316 -157.918658) (xy 398.133316 -157.410658) (xy 398.514316 -157.410658) (xy 398.514316 -157.918658)
				)
			)
		)
		(zone
			(layer "F.Cu")
			(hatch none 0.5)
			(connect_pads
				(clearance 0)
			)
			(min_thickness 0.25)
			(keepout
				(tracks allowed)
				(vias not_allowed)
				(pads allowed)
				(copperpour not_allowed)
				(footprints allowed)
			)
			(placement
				(enabled no)
				(sheetname "")
			)
			(fill
				(thermal_gap 0.5)
				(thermal_bridge_width 0.5)
				(island_removal_mode 0)
			)
			(polygon
				(pts
					(xy 398.514316 -157.918658) (xy 398.514316 -157.410658) (xy 398.133316 -157.410658) (xy 398.133316 -157.918658)
				)
			)
		)
	)
)
